(kicad_pcb
	(version 20260206)
	(generator "pcbnew")
	(generator_version "10.0")
	(general
		(thickness 1.6)
		(legacy_teardrops no)
	)
	(paper "A4")
	(title_block
		(title "v1-chassis-manager — T6M_CM_d_v01_1031_1645.brd")
		(comment 1 "Open CloudServer (Microsoft) / footprint 1507 of 2512 (U2), pads 1185-1283 of 1283")
	)
	(layers
		(0 "F.Cu" signal "TOP")
		(4 "In1.Cu" signal "GND1")
		(6 "In2.Cu" signal "IN1")
		(8 "In3.Cu" signal "VCC1")
		(10 "In4.Cu" signal "VCC2")
		(12 "In5.Cu" signal "GND2")
		(14 "In6.Cu" signal "IN2")
		(16 "In7.Cu" signal "IN3")
		(18 "In8.Cu" signal "GND3")
		(2 "B.Cu" signal "BOTTOM")
		(9 "F.Adhes" user "F.Adhesive")
		(11 "B.Adhes" user "B.Adhesive")
		(13 "F.Paste" user "Package Geometry/Pastemask Top")
		(15 "B.Paste" user "Package Geometry/Pastemask Bottom")
		(5 "F.SilkS" user "Ref Des/Silkscreen Top")
		(7 "B.SilkS" user "Ref Des/Silkscreen Bottom")
		(1 "F.Mask" user "Board Geometry/Soldermask Top")
		(3 "B.Mask" user "Board Geometry/Soldermask Bottom")
		(17 "Dwgs.User" user "User.Drawings")
		(19 "Cmts.User" user "User.Comments")
		(21 "Eco1.User" user "User.Eco1")
		(23 "Eco2.User" user "User.Eco2")
		(25 "Edge.Cuts" user "Board Geometry/Outline")
		(27 "Margin" user)
		(31 "F.CrtYd" user "Package Geometry/Place Bound Top")
		(29 "B.CrtYd" user "Package Geometry/Place Bound Bottom")
		(35 "F.Fab" user "Ref Des/Assembly Top")
		(33 "B.Fab" user "Ref Des/Assembly Bottom")
	)
	(footprint ""
		(layer "F.Cu")
		(at 58.000646 -75.799442)
		(property "Reference" "U2"
			(at -20.2438 -18.364708 0)
			(unlocked yes)
			(layer "F.SilkS")
			(effects
				(font
					(size 1.6002 1.1938)
					(thickness 0.1524)
				)
				(justify left)
			)
		)
		(property "Value" ""
			(at 0 0 0)
			(layer "F.Fab")
			(effects
				(font
					(size 1.27 1.27)
				)
			)
		)
		(duplicate_pad_numbers_are_jumpers no)
		(pad "T55" smd circle
			(at 10.677398 -5.728716)
			(size 0.3048 0.3048)
			(layers "F.Cu" "F.Mask" "F.Paste")
			(net "GND")
		)
		(pad "T56" smd circle
			(at 11.439398 -5.728716)
			(size 0.3048 0.3048)
			(layers "F.Cu" "F.Mask" "F.Paste")
			(net "IRQ_LVC3_CPU_NODE1_WAKE_L")
		)
		(pad "T58" smd circle
			(at 12.201398 -5.728716)
			(size 0.3048 0.3048)
			(layers "F.Cu" "F.Mask" "F.Paste")
			(net "FM_CPLD_NODE1_CPU_RESET_L")
		)
		(pad "T59" smd circle
			(at 12.963398 -5.728716)
			(size 0.3048 0.3048)
			(layers "F.Cu" "F.Mask" "F.Paste")
			(net "GND")
		)
		(pad "T62" smd circle
			(at 14.013688 -5.819648)
			(size 0.3048 0.3048)
			(layers "F.Cu" "F.Mask" "F.Paste")
			(net "GND")
		)
		(pad "T64" smd circle
			(at 15.247112 -5.789422)
			(size 0.3048 0.3048)
			(layers "F.Cu" "F.Mask" "F.Paste")
			(net "GND")
		)
		(pad "U2" smd circle
			(at -15.752318 -5.12064)
			(size 0.3048 0.3048)
			(layers "F.Cu" "F.Mask" "F.Paste")
			(net "PD_CPU_NODE1_RP2_PERN")
		)
		(pad "U4" smd circle
			(at -14.794738 -5.067808)
			(size 0.3048 0.3048)
			(layers "F.Cu" "F.Mask" "F.Paste")
			(net "PD_CPU_NODE1_RP2_PERP")
		)
		(pad "U8" smd circle
			(at -12.963398 -5.48894)
			(size 0.3048 0.3048)
			(layers "F.Cu" "F.Mask" "F.Paste")
			(net "GND")
		)
		(pad "U9" smd circle
			(at -12.201398 -5.48894)
			(size 0.3048 0.3048)
			(layers "F.Cu" "F.Mask" "F.Paste")
			(net "Net_408")
		)
		(pad "U11" smd circle
			(at -11.439398 -5.48894)
			(size 0.3048 0.3048)
			(layers "F.Cu" "F.Mask" "F.Paste")
			(net "Net_407")
		)
		(pad "U12" smd circle
			(at -10.677398 -5.48894)
			(size 0.3048 0.3048)
			(layers "F.Cu" "F.Mask" "F.Paste")
			(net "GND")
		)
		(pad "U14" smd circle
			(at -9.915398 -5.48894)
			(size 0.3048 0.3048)
			(layers "F.Cu" "F.Mask" "F.Paste")
			(net "Net_404")
		)
		(pad "U15" smd circle
			(at -9.153398 -5.48894)
			(size 0.3048 0.3048)
			(layers "F.Cu" "F.Mask" "F.Paste")
			(net "Net_402")
		)
		(pad "U62" smd circle
			(at 14.063218 -5.117338)
			(size 0.3048 0.3048)
			(layers "F.Cu" "F.Mask" "F.Paste")
			(net "PV_VCCP_NODE1")
		)
		(pad "U63" smd circle
			(at 14.751558 -5.286248)
			(size 0.3048 0.3048)
			(layers "F.Cu" "F.Mask" "F.Paste")
			(net "PV_VCCP_NODE1")
		)
		(pad "U65" smd circle
			(at 15.805658 -5.366004)
			(size 0.3048 0.3048)
			(layers "F.Cu" "F.Mask" "F.Paste")
			(net "PV_VCCP_NODE1")
		)
		(pad "V5" smd circle
			(at -14.063218 -4.910074)
			(size 0.3048 0.3048)
			(layers "F.Cu" "F.Mask" "F.Paste")
			(net "PD_CPU_NODE1_RP2_PERP")
		)
		(pad "V20" smd circle
			(at -6.726174 -4.8006 180)
			(size 0.3048 0.3048)
			(layers "F.Cu" "F.Mask" "F.Paste")
			(net "CLK_100M_CPU_NODE1_DN")
		)
		(pad "V21" smd circle
			(at -6.00075 -4.8006)
			(size 0.381 0.381)
			(layers "F.Cu" "F.Mask" "F.Paste")
			(net "CLK_100M_CPU_NODE1_DP")
		)
		(pad "V23" smd circle
			(at -5.20065 -4.8006)
			(size 0.381 0.381)
			(layers "F.Cu" "F.Mask" "F.Paste")
			(net "GND")
		)
		(pad "V25" smd circle
			(at -4.40055 -4.8006)
			(size 0.381 0.381)
			(layers "F.Cu" "F.Mask" "F.Paste")
			(net "GND")
		)
		(pad "V26" smd circle
			(at -3.60045 -4.8006)
			(size 0.381 0.381)
			(layers "F.Cu" "F.Mask" "F.Paste")
			(net "GND")
		)
		(pad "V28" smd circle
			(at -2.80035 -4.8006)
			(size 0.381 0.381)
			(layers "F.Cu" "F.Mask" "F.Paste")
			(net "GND")
		)
		(pad "V29" smd circle
			(at -2.00025 -4.8006)
			(size 0.381 0.381)
			(layers "F.Cu" "F.Mask" "F.Paste")
			(net "GND")
		)
		(pad "V31" smd circle
			(at -1.20015 -4.8006)
			(size 0.381 0.381)
			(layers "F.Cu" "F.Mask" "F.Paste")
			(net "GND")
		)
		(pad "V32" smd circle
			(at -0.40005 -4.8006)
			(size 0.381 0.381)
			(layers "F.Cu" "F.Mask" "F.Paste")
			(net "P1V8_NODE1")
		)
		(pad "V34" smd circle
			(at 0.40005 -4.8006)
			(size 0.381 0.381)
			(layers "F.Cu" "F.Mask" "F.Paste")
			(net "GND")
		)
		(pad "V36" smd circle
			(at 1.20015 -4.8006)
			(size 0.381 0.381)
			(layers "F.Cu" "F.Mask" "F.Paste")
			(net "P3V3_NODE1")
		)
		(pad "V38" smd circle
			(at 2.00025 -4.8006)
			(size 0.381 0.381)
			(layers "F.Cu" "F.Mask" "F.Paste")
			(net "GND")
		)
		(pad "V39" smd circle
			(at 2.80035 -4.8006)
			(size 0.381 0.381)
			(layers "F.Cu" "F.Mask" "F.Paste")
			(net "GND")
		)
		(pad "V41" smd circle
			(at 3.60045 -4.8006)
			(size 0.381 0.381)
			(layers "F.Cu" "F.Mask" "F.Paste")
			(net "GND")
		)
		(pad "V42" smd circle
			(at 4.40055 -4.8006)
			(size 0.381 0.381)
			(layers "F.Cu" "F.Mask" "F.Paste")
			(net "GND")
		)
		(pad "V44" smd circle
			(at 5.20065 -4.8006)
			(size 0.381 0.381)
			(layers "F.Cu" "F.Mask" "F.Paste")
			(net "GND")
		)
		(pad "V46" smd circle
			(at 6.00075 -4.8006)
			(size 0.381 0.381)
			(layers "F.Cu" "F.Mask" "F.Paste")
			(net "GND")
		)
		(pad "V63" smd circle
			(at 14.542516 -4.606544)
			(size 0.3048 0.3048)
			(layers "F.Cu" "F.Mask" "F.Paste")
			(net "PV_VCCP_NODE1")
		)
		(pad "V64" smd circle
			(at 15.304516 -4.555744)
			(size 0.3048 0.3048)
			(layers "F.Cu" "F.Mask" "F.Paste")
			(net "PV_VCCP_NODE1")
		)
		(pad "V66" smd oval
			(at 16.249396 -4.606544 90)
			(size 0.254 0.3429)
			(layers "F.Cu" "F.Mask" "F.Paste")
			(net "PV_VCCP_NODE1")
		)
		(pad "W1" smd oval
			(at -16.249396 -4.39928 270)
			(size 0.254 0.3429)
			(layers "F.Cu" "F.Mask" "F.Paste")
			(net "PD_CPU_NODE1_W1")
		)
		(pad "W3" smd circle
			(at -15.304516 -4.45008)
			(size 0.3048 0.3048)
			(layers "F.Cu" "F.Mask" "F.Paste")
			(net "GND")
		)
		(pad "W4" smd circle
			(at -14.542516 -4.39928)
			(size 0.3048 0.3048)
			(layers "F.Cu" "F.Mask" "F.Paste")
			(net "PD_CPU_NODE1_RP2_PERN")
		)
		(pad "W7" smd circle
			(at -13.344398 -4.202684)
			(size 0.3048 0.3048)
			(layers "F.Cu" "F.Mask" "F.Paste")
			(net "GND")
		)
		(pad "W8" smd circle
			(at -12.582398 -4.202684)
			(size 0.3048 0.3048)
			(layers "F.Cu" "F.Mask" "F.Paste")
			(net "Net_399")
		)
		(pad "W10" smd circle
			(at -11.820398 -4.202684)
			(size 0.3048 0.3048)
			(layers "F.Cu" "F.Mask" "F.Paste")
			(net "GND")
		)
		(pad "W11" smd circle
			(at -11.058398 -4.202684)
			(size 0.3048 0.3048)
			(layers "F.Cu" "F.Mask" "F.Paste")
			(net "SMB_CPU_NODE1_XDP_CLK_R")
		)
		(pad "W13" smd circle
			(at -10.296398 -4.202684)
			(size 0.3048 0.3048)
			(layers "F.Cu" "F.Mask" "F.Paste")
			(net "SMB_CPU_NODE1_MEM_ICS_DAT_R")
		)
		(pad "W14" smd circle
			(at -9.534398 -4.202684)
			(size 0.3048 0.3048)
			(layers "F.Cu" "F.Mask" "F.Paste")
			(net "GND")
		)
		(pad "W16" smd circle
			(at -8.772398 -4.202684)
			(size 0.3048 0.3048)
			(layers "F.Cu" "F.Mask" "F.Paste")
			(net "SMB_CPU_NODE1_BMC_DAT_RR")
		)
		(pad "W17" smd circle
			(at -8.010398 -4.202684)
			(size 0.3048 0.3048)
			(layers "F.Cu" "F.Mask" "F.Paste")
			(net "SMB_CPU_NODE1_XDP_DAT_R")
		)
		(pad "W19" smd circle
			(at -7.248398 -4.202684)
			(size 0.3048 0.3048)
			(layers "F.Cu" "F.Mask" "F.Paste")
			(net "GND")
		)
		(pad "W21" smd circle
			(at -6.00075 -4.0005)
			(size 0.381 0.381)
			(layers "F.Cu" "F.Mask" "F.Paste")
			(net "GND")
		)
		(pad "W23" smd circle
			(at -5.20065 -4.0005)
			(size 0.381 0.381)
			(layers "F.Cu" "F.Mask" "F.Paste")
			(net "GND")
		)
		(pad "W25" smd circle
			(at -4.40055 -4.0005)
			(size 0.381 0.381)
			(layers "F.Cu" "F.Mask" "F.Paste")
			(net "GND")
		)
		(pad "W26" smd circle
			(at -3.60045 -4.0005)
			(size 0.381 0.381)
			(layers "F.Cu" "F.Mask" "F.Paste")
			(net "GND")
		)
		(pad "W28" smd circle
			(at -2.80035 -4.0005)
			(size 0.381 0.381)
			(layers "F.Cu" "F.Mask" "F.Paste")
			(net "GND")
		)
		(pad "W29" smd circle
			(at -2.00025 -4.0005)
			(size 0.381 0.381)
			(layers "F.Cu" "F.Mask" "F.Paste")
			(net "GND")
		)
		(pad "W31" smd circle
			(at -1.20015 -4.0005)
			(size 0.381 0.381)
			(layers "F.Cu" "F.Mask" "F.Paste")
			(net "GND")
		)
		(pad "W32" smd circle
			(at -0.40005 -4.0005)
			(size 0.381 0.381)
			(layers "F.Cu" "F.Mask" "F.Paste")
			(net "P1V05_NODE1")
		)
		(pad "W34" smd circle
			(at 0.40005 -4.0005)
			(size 0.381 0.381)
			(layers "F.Cu" "F.Mask" "F.Paste")
			(net "GND")
		)
		(pad "W36" smd circle
			(at 1.20015 -4.0005)
			(size 0.381 0.381)
			(layers "F.Cu" "F.Mask" "F.Paste")
			(net "P1V05_NODE1")
		)
		(pad "W38" smd circle
			(at 2.00025 -4.0005)
			(size 0.381 0.381)
			(layers "F.Cu" "F.Mask" "F.Paste")
			(net "GND")
		)
		(pad "W39" smd circle
			(at 2.80035 -4.0005)
			(size 0.381 0.381)
			(layers "F.Cu" "F.Mask" "F.Paste")
			(net "P1V05_NODE1")
		)
		(pad "W41" smd circle
			(at 3.60045 -4.0005)
			(size 0.381 0.381)
			(layers "F.Cu" "F.Mask" "F.Paste")
			(net "GND")
		)
		(pad "W42" smd circle
			(at 4.40055 -4.0005)
			(size 0.381 0.381)
			(layers "F.Cu" "F.Mask" "F.Paste")
			(net "P1V05_NODE1")
		)
		(pad "W44" smd circle
			(at 5.20065 -4.0005)
			(size 0.381 0.381)
			(layers "F.Cu" "F.Mask" "F.Paste")
			(net "PV_VCCP_NODE1")
		)
		(pad "W46" smd circle
			(at 6.00075 -4.0005)
			(size 0.381 0.381)
			(layers "F.Cu" "F.Mask" "F.Paste")
			(net "PV_VCCP_NODE1")
		)
		(pad "W48" smd circle
			(at 7.248398 -4.44246)
			(size 0.3048 0.3048)
			(layers "F.Cu" "F.Mask" "F.Paste")
			(net "PV_VCCP_NODE1")
		)
		(pad "W50" smd circle
			(at 8.010398 -4.44246)
			(size 0.3048 0.3048)
			(layers "F.Cu" "F.Mask" "F.Paste")
			(net "PV_VCCP_NODE1")
		)
		(pad "W51" smd circle
			(at 8.772398 -4.44246)
			(size 0.3048 0.3048)
			(layers "F.Cu" "F.Mask" "F.Paste")
			(net "GND")
		)
		(pad "W53" smd circle
			(at 9.534398 -4.44246)
			(size 0.3048 0.3048)
			(layers "F.Cu" "F.Mask" "F.Paste")
			(net "PV_VCCP_NODE1")
		)
		(pad "W54" smd circle
			(at 10.296398 -4.44246)
			(size 0.3048 0.3048)
			(layers "F.Cu" "F.Mask" "F.Paste")
			(net "PV_VCCP_NODE1")
		)
		(pad "W56" smd circle
			(at 11.058398 -4.44246)
			(size 0.3048 0.3048)
			(layers "F.Cu" "F.Mask" "F.Paste")
			(net "GND")
		)
		(pad "W57" smd circle
			(at 11.820398 -4.44246)
			(size 0.3048 0.3048)
			(layers "F.Cu" "F.Mask" "F.Paste")
			(net "PV_VCCP_NODE1")
		)
		(pad "W59" smd circle
			(at 12.582398 -4.44246)
			(size 0.3048 0.3048)
			(layers "F.Cu" "F.Mask" "F.Paste")
			(net "PV_VCCP_NODE1")
		)
		(pad "W60" smd circle
			(at 13.344398 -4.44246)
			(size 0.3048 0.3048)
			(layers "F.Cu" "F.Mask" "F.Paste")
			(net "GND")
		)
		(pad "W62" smd circle
			(at 14.063218 -4.09575)
			(size 0.3048 0.3048)
			(layers "F.Cu" "F.Mask" "F.Paste")
			(net "GND")
		)
		(pad "Y2" smd circle
			(at -15.805658 -3.63982)
			(size 0.3048 0.3048)
			(layers "F.Cu" "F.Mask" "F.Paste")
			(net "PD_CPU_NODE1_Y2")
		)
		(pad "Y4" smd circle
			(at -14.751558 -3.719576)
			(size 0.3048 0.3048)
			(layers "F.Cu" "F.Mask" "F.Paste")
			(net "GND")
		)
		(pad "Y5" smd circle
			(at -14.063218 -3.888486)
			(size 0.3048 0.3048)
			(layers "F.Cu" "F.Mask" "F.Paste")
			(net "GND")
		)
		(pad "Y7" smd circle
			(at -13.344398 -3.50266)
			(size 0.3048 0.3048)
			(layers "F.Cu" "F.Mask" "F.Paste")
			(net "GND")
		)
		(pad "Y8" smd circle
			(at -12.582398 -3.50266)
			(size 0.3048 0.3048)
			(layers "F.Cu" "F.Mask" "F.Paste")
			(net "Net_370")
		)
		(pad "Y10" smd circle
			(at -11.820398 -3.50266)
			(size 0.3048 0.3048)
			(layers "F.Cu" "F.Mask" "F.Paste")
			(net "GND")
		)
		(pad "Y11" smd circle
			(at -11.058398 -3.50266)
			(size 0.3048 0.3048)
			(layers "F.Cu" "F.Mask" "F.Paste")
			(net "SMB_CPU_NODE1_MEM_ICS_CLK_R")
		)
		(pad "Y13" smd circle
			(at -10.296398 -3.50266)
			(size 0.3048 0.3048)
			(layers "F.Cu" "F.Mask" "F.Paste")
			(net "SMB_CPU_NODE1_BMC_CLK_RR")
		)
		(pad "Y14" smd circle
			(at -9.534398 -3.50266)
			(size 0.3048 0.3048)
			(layers "F.Cu" "F.Mask" "F.Paste")
			(net "GND")
		)
		(pad "Y16" smd circle
			(at -8.772398 -3.50266)
			(size 0.3048 0.3048)
			(layers "F.Cu" "F.Mask" "F.Paste")
			(net "GND")
		)
		(pad "Y17" smd circle
			(at -8.010398 -3.50266)
			(size 0.3048 0.3048)
			(layers "F.Cu" "F.Mask" "F.Paste")
			(net "GND")
		)
		(pad "Y19" smd circle
			(at -7.248398 -3.50266)
			(size 0.3048 0.3048)
			(layers "F.Cu" "F.Mask" "F.Paste")
			(net "GND")
		)
		(pad "Y48" smd circle
			(at 7.248398 -3.742436)
			(size 0.3048 0.3048)
			(layers "F.Cu" "F.Mask" "F.Paste")
			(net "PV_VCCP_NODE1")
		)
		(pad "Y50" smd circle
			(at 8.010398 -3.742436)
			(size 0.3048 0.3048)
			(layers "F.Cu" "F.Mask" "F.Paste")
			(net "PV_VCCP_NODE1")
		)
		(pad "Y51" smd circle
			(at 8.772398 -3.742436)
			(size 0.3048 0.3048)
			(layers "F.Cu" "F.Mask" "F.Paste")
			(net "GND")
		)
		(pad "Y53" smd circle
			(at 9.534398 -3.742436)
			(size 0.3048 0.3048)
			(layers "F.Cu" "F.Mask" "F.Paste")
			(net "PV_VCCP_NODE1")
		)
		(pad "Y54" smd circle
			(at 10.296398 -3.742436)
			(size 0.3048 0.3048)
			(layers "F.Cu" "F.Mask" "F.Paste")
			(net "PV_VCCP_NODE1")
		)
		(pad "Y56" smd circle
			(at 11.058398 -3.742436)
			(size 0.3048 0.3048)
			(layers "F.Cu" "F.Mask" "F.Paste")
			(net "GND")
		)
		(pad "Y57" smd circle
			(at 11.820398 -3.742436)
			(size 0.3048 0.3048)
			(layers "F.Cu" "F.Mask" "F.Paste")
			(net "PV_VCCP_NODE1")
		)
		(pad "Y59" smd circle
			(at 12.582398 -3.742436)
			(size 0.3048 0.3048)
			(layers "F.Cu" "F.Mask" "F.Paste")
			(net "PV_VCCP_NODE1")
		)
		(pad "Y60" smd circle
			(at 13.344398 -3.742436)
			(size 0.3048 0.3048)
			(layers "F.Cu" "F.Mask" "F.Paste")
			(net "GND")
		)
		(pad "Y63" smd circle
			(at 14.794738 -3.938016)
			(size 0.3048 0.3048)
			(layers "F.Cu" "F.Mask" "F.Paste")
			(net "GND")
		)
		(pad "Y65" smd circle
			(at 15.752318 -3.885184)
			(size 0.3048 0.3048)
			(layers "F.Cu" "F.Mask" "F.Paste")
			(net "GND")
		)
	)
)
